(kicad_pcb
	(version 20260206)
	(generator "pcbnew")
	(generator_version "10.0")
	(general
		(thickness 1.6)
		(legacy_teardrops no)
	)
	(paper "A4")
	(title_block
		(title "dpb — 14545-sa.0730WZS0815.brd")
		(comment 1 "Honey Badger (Wiwynn) / footprints 344-348 of 1066")
	)
	(layers
		(0 "F.Cu" signal "TOP")
		(4 "In1.Cu" signal "L2GND")
		(6 "In2.Cu" signal "L3")
		(8 "In3.Cu" signal "L4VCC")
		(10 "In4.Cu" signal "L5VCC")
		(12 "In5.Cu" signal "L6")
		(14 "In6.Cu" signal "L7GND")
		(2 "B.Cu" signal "BOTTOM")
		(9 "F.Adhes" user "F.Adhesive")
		(11 "B.Adhes" user "B.Adhesive")
		(13 "F.Paste" user "Package Geometry/Pastemask Top")
		(15 "B.Paste" user "Package Geometry/Pastemask Bottom")
		(5 "F.SilkS" user "Ref Des/Silkscreen Top")
		(7 "B.SilkS" user "Ref Des/Silkscreen Bottom")
		(1 "F.Mask" user "Board Geometry/Soldermask Top")
		(3 "B.Mask" user "Board Geometry/Soldermask Bottom")
		(17 "Dwgs.User" user "User.Drawings")
		(19 "Cmts.User" user "User.Comments")
		(21 "Eco1.User" user "User.Eco1")
		(23 "Eco2.User" user "User.Eco2")
		(25 "Edge.Cuts" user "Board Geometry/Outline")
		(27 "Margin" user)
		(31 "F.CrtYd" user "Package Geometry/Place Bound Top")
		(29 "B.CrtYd" user "Package Geometry/Place Bound Bottom")
		(35 "F.Fab" user "Ref Des/Assembly Top")
		(33 "B.Fab" user "Ref Des/Assembly Bottom")
	)
	(footprint ""
		(layer "F.Cu")
		(at 233.120946 -452.374 90)
		(property "Reference" "Q34"
			(at 0 0 90)
			(layer "F.SilkS")
			(hide yes)
			(effects
				(font
					(size 1.27 1.27)
				)
			)
		)
		(property "Value" "PMBS3904-1-GP"
			(at 0 -9.0932 90)
			(unlocked yes)
			(layer "F.Fab")
			(hide yes)
			(effects
				(font
					(size 1.016 1.016)
					(thickness 0.1524)
				)
			)
		)
		(property "Device Type" "SOT-23-10H44"
			(at 0 -10.6172 90)
			(unlocked yes)
			(layer "F.Fab")
			(hide yes)
			(effects
				(font
					(size 1.016 1.016)
					(thickness 0.1524)
				)
			)
		)
		(duplicate_pad_numbers_are_jumpers no)
		(fp_line
			(start 1.651 -1.778)
			(end -1.651 -1.778)
			(stroke
				(width 0.1524)
				(type default)
			)
			(layer "F.SilkS")
		)
		(fp_line
			(start -1.651 -1.778)
			(end -1.651 1.778)
			(stroke
				(width 0.1524)
				(type default)
			)
			(layer "F.SilkS")
		)
		(fp_line
			(start 1.651 1.778)
			(end 1.651 -1.778)
			(stroke
				(width 0.1524)
				(type default)
			)
			(layer "F.SilkS")
		)
		(fp_line
			(start -1.651 1.778)
			(end 1.651 1.778)
			(stroke
				(width 0.1524)
				(type default)
			)
			(layer "F.SilkS")
		)
		(fp_line
			(start -0.9906 1.86309)
			(end -0.701294 2.15265)
			(stroke
				(width 0.0127)
				(type default)
			)
			(layer "F.SilkS")
		)
		(fp_line
			(start -0.994156 1.8669)
			(end -0.987044 1.8669)
			(stroke
				(width 0.0127)
				(type default)
			)
			(layer "F.SilkS")
		)
		(fp_line
			(start -1.003808 1.876552)
			(end -0.977646 1.876552)
			(stroke
				(width 0.0127)
				(type default)
			)
			(layer "F.SilkS")
		)
		(fp_line
			(start -0.635 1.8796)
			(end -1.7526 1.8796)
			(stroke
				(width 0.3302)
				(type default)
			)
			(layer "F.SilkS")
		)
		(fp_line
			(start -1.7526 1.8796)
			(end -1.7526 0.9906)
			(stroke
				(width 0.3302)
				(type default)
			)
			(layer "F.SilkS")
		)
		(fp_line
			(start -1.013206 1.88595)
			(end -0.967994 1.88595)
			(stroke
				(width 0.0127)
				(type default)
			)
			(layer "F.SilkS")
		)
		(fp_line
			(start -1.022858 1.895602)
			(end -0.958596 1.895602)
			(stroke
				(width 0.0127)
				(type default)
			)
			(layer "F.SilkS")
		)
		(fp_line
			(start -1.032256 1.905)
			(end -0.948944 1.905)
			(stroke
				(width 0.0127)
				(type default)
			)
			(layer "F.SilkS")
		)
		(fp_line
			(start -1.041908 1.914652)
			(end -0.939546 1.914652)
			(stroke
				(width 0.0127)
				(type default)
			)
			(layer "F.SilkS")
		)
		(fp_line
			(start -1.051306 1.92405)
			(end -0.929894 1.92405)
			(stroke
				(width 0.0127)
				(type default)
			)
			(layer "F.SilkS")
		)
		(fp_line
			(start -1.060958 1.933702)
			(end -0.920496 1.933702)
			(stroke
				(width 0.0127)
				(type default)
			)
			(layer "F.SilkS")
		)
		(fp_line
			(start -1.070356 1.9431)
			(end -0.910844 1.9431)
			(stroke
				(width 0.0127)
				(type default)
			)
			(layer "F.SilkS")
		)
		(fp_line
			(start -1.080008 1.952752)
			(end -0.901446 1.952752)
			(stroke
				(width 0.0127)
				(type default)
			)
			(layer "F.SilkS")
		)
		(fp_line
			(start -1.089406 1.96215)
			(end -0.891794 1.96215)
			(stroke
				(width 0.0127)
				(type default)
			)
			(layer "F.SilkS")
		)
		(fp_line
			(start -1.099058 1.971802)
			(end -0.882396 1.971802)
			(stroke
				(width 0.0127)
				(type default)
			)
			(layer "F.SilkS")
		)
		(fp_line
			(start -1.108456 1.9812)
			(end -0.872744 1.9812)
			(stroke
				(width 0.0127)
				(type default)
			)
			(layer "F.SilkS")
		)
		(fp_line
			(start -1.118108 1.990852)
			(end -0.863346 1.990852)
			(stroke
				(width 0.0127)
				(type default)
			)
			(layer "F.SilkS")
		)
		(fp_line
			(start -1.127506 2.00025)
			(end -0.853694 2.00025)
			(stroke
				(width 0.0127)
				(type default)
			)
			(layer "F.SilkS")
		)
		(fp_line
			(start -1.137158 2.009902)
			(end -0.844296 2.009902)
			(stroke
				(width 0.0127)
				(type default)
			)
			(layer "F.SilkS")
		)
		(fp_line
			(start -1.146556 2.0193)
			(end -0.834644 2.0193)
			(stroke
				(width 0.0127)
				(type default)
			)
			(layer "F.SilkS")
		)
		(fp_line
			(start -1.156208 2.028952)
			(end -0.825246 2.028952)
			(stroke
				(width 0.0127)
				(type default)
			)
			(layer "F.SilkS")
		)
		(fp_line
			(start -1.165606 2.03835)
			(end -0.815594 2.03835)
			(stroke
				(width 0.0127)
				(type default)
			)
			(layer "F.SilkS")
		)
		(fp_line
			(start -1.175258 2.048002)
			(end -0.806196 2.048002)
			(stroke
				(width 0.0127)
				(type default)
			)
			(layer "F.SilkS")
		)
		(fp_line
			(start -1.184656 2.0574)
			(end -0.796544 2.0574)
			(stroke
				(width 0.0127)
				(type default)
			)
			(layer "F.SilkS")
		)
		(fp_line
			(start -1.194308 2.067052)
			(end -0.787146 2.067052)
			(stroke
				(width 0.0127)
				(type default)
			)
			(layer "F.SilkS")
		)
		(fp_line
			(start -1.203706 2.07645)
			(end -0.777494 2.07645)
			(stroke
				(width 0.0127)
				(type default)
			)
			(layer "F.SilkS")
		)
		(fp_line
			(start -1.213358 2.086102)
			(end -0.768096 2.086102)
			(stroke
				(width 0.0127)
				(type default)
			)
			(layer "F.SilkS")
		)
		(fp_line
			(start -1.222756 2.0955)
			(end -0.758444 2.0955)
			(stroke
				(width 0.0127)
				(type default)
			)
			(layer "F.SilkS")
		)
		(fp_line
			(start -1.232408 2.105152)
			(end -0.749046 2.105152)
			(stroke
				(width 0.0127)
				(type default)
			)
			(layer "F.SilkS")
		)
		(fp_line
			(start -1.241806 2.11455)
			(end -0.739394 2.11455)
			(stroke
				(width 0.0127)
				(type default)
			)
			(layer "F.SilkS")
		)
		(fp_line
			(start -1.251458 2.124202)
			(end -0.729996 2.124202)
			(stroke
				(width 0.0127)
				(type default)
			)
			(layer "F.SilkS")
		)
		(fp_line
			(start -1.260856 2.1336)
			(end -0.720344 2.1336)
			(stroke
				(width 0.0127)
				(type default)
			)
			(layer "F.SilkS")
		)
		(fp_line
			(start -0.719074 2.145538)
			(end -1.265936 2.14122)
			(stroke
				(width 0.0127)
				(type default)
			)
			(layer "F.SilkS")
		)
		(fp_line
			(start -1.279398 2.152142)
			(end -0.9906 1.86309)
			(stroke
				(width 0.0127)
				(type default)
			)
			(layer "F.SilkS")
		)
		(fp_line
			(start -0.71628 2.15265)
			(end -1.26492 2.15265)
			(stroke
				(width 0.0127)
				(type default)
			)
			(layer "F.SilkS")
		)
		(fp_line
			(start -1.279144 2.15265)
			(end -0.701294 2.15265)
			(stroke
				(width 0.0127)
				(type default)
			)
			(layer "F.SilkS")
		)
		(fp_poly
			(pts
				(xy -1.285748 2.159) (xy -1.285748 1.8796) (xy -1.778 1.8796) (xy -1.778 -1.8796) (xy 1.778 -1.8796)
				(xy 1.778 1.8796) (xy -0.694944 1.8796) (xy -0.694944 2.159)
			)
			(stroke
				(width 0)
				(type default)
			)
			(fill no)
			(layer "F.CrtYd")
		)
		(fp_poly
			(pts
				(xy -1.285748 2.159) (xy -1.285748 1.8796) (xy -1.778 1.8796) (xy -1.778 -1.8796) (xy 1.778 -1.8796)
				(xy 1.778 1.8796) (xy -0.694944 1.8796) (xy -0.694944 2.159)
			)
			(stroke
				(width 0)
				(type default)
			)
			(fill no)
			(layer "F.Fab")
		)
		(pad "1" smd rect
			(at -0.98425 0.9525 90)
			(size 0.762 1.143)
			(layers "F.Cu" "F.Mask" "F.Paste")
			(net "FLT_HDD0_B")
		)
		(pad "2" smd rect
			(at 0.98425 0.9525 90)
			(size 0.762 1.143)
			(layers "F.Cu" "F.Mask" "F.Paste")
			(net "GND")
		)
		(pad "3" smd rect
			(at 0 -0.9525 90)
			(size 0.762 1.143)
			(layers "F.Cu" "F.Mask" "F.Paste")
			(net "DRIVE_ACT_0")
		)
	)
	(footprint ""
		(layer "F.Cu")
		(at 211.3534 -440.563 -90)
		(property "Reference" "PR57"
			(at 0 0 270)
			(layer "F.SilkS")
			(hide yes)
			(effects
				(font
					(size 1.27 1.27)
				)
			)
		)
		(property "Value" "0R0805-PAD-2-GP-U"
			(at 0.0254 -2.8702 270)
			(unlocked yes)
			(layer "F.Fab")
			(hide yes)
			(effects
				(font
					(size 1.016 1.016)
					(thickness 0.1524)
				)
			)
		)
		(property "Device Type" "0R0805-PAD-1-U"
			(at 0.0254 -4.3942 270)
			(unlocked yes)
			(layer "F.Fab")
			(hide yes)
			(effects
				(font
					(size 1.016 1.016)
					(thickness 0.1524)
				)
			)
		)
		(duplicate_pad_numbers_are_jumpers no)
		(fp_line
			(start -0.889 1.7018)
			(end -0.889 -1.7018)
			(stroke
				(width 0.1524)
				(type default)
			)
			(layer "F.SilkS")
		)
		(fp_line
			(start 0.889 1.7018)
			(end -0.889 1.7018)
			(stroke
				(width 0.1524)
				(type default)
			)
			(layer "F.SilkS")
		)
		(fp_line
			(start -0.889 -1.7018)
			(end 0.889 -1.7018)
			(stroke
				(width 0.1524)
				(type default)
			)
			(layer "F.SilkS")
		)
		(fp_line
			(start 0.889 -1.7018)
			(end 0.889 1.7018)
			(stroke
				(width 0.1524)
				(type default)
			)
			(layer "F.SilkS")
		)
		(fp_rect
			(start -0.9652 1.778)
			(end 0.9652 -1.778)
			(stroke
				(width 0)
				(type default)
			)
			(fill no)
			(layer "F.CrtYd")
		)
		(fp_rect
			(start -0.9652 1.778)
			(end 0.9652 -1.778)
			(stroke
				(width 0)
				(type default)
			)
			(fill no)
			(layer "F.Fab")
		)
		(pad "1" smd rect
			(at 0 -0.9652 270)
			(size 1.397 1.5621)
			(drill
				(offset 0 0.20955)
			)
			(layers "F.Cu" "F.Mask" "F.Paste")
			(net "P3V3_LX_COOPER")
		)
		(pad "2" smd rect
			(at 0 0.9652 270)
			(size 1.397 1.568704)
			(drill
				(offset 0 -0.206248)
			)
			(layers "F.Cu" "F.Mask" "F.Paste")
			(net "P3V3")
		)
	)
	(footprint ""
		(layer "F.Cu")
		(at 72.226932 -496.145312)
		(property "Reference" "R442"
			(at 0 0 0)
			(layer "F.SilkS")
			(hide yes)
			(effects
				(font
					(size 1.27 1.27)
				)
			)
		)
		(property "Value" "4K7R2J-2-GP"
			(at 0.064008 -3.993896 0)
			(unlocked yes)
			(layer "F.Fab")
			(hide yes)
			(effects
				(font
					(size 1.016 1.016)
					(thickness 0.1524)
				)
			)
		)
		(property "Device Type" "R402H16"
			(at 0.064008 -5.517896 0)
			(unlocked yes)
			(layer "F.Fab")
			(hide yes)
			(effects
				(font
					(size 1.016 1.016)
					(thickness 0.1524)
				)
			)
		)
		(duplicate_pad_numbers_are_jumpers no)
		(fp_line
			(start -0.508 -0.9398)
			(end -0.508 0.9398)
			(stroke
				(width 0.1524)
				(type default)
			)
			(layer "F.SilkS")
		)
		(fp_line
			(start 0.508 -0.9398)
			(end -0.508 -0.9398)
			(stroke
				(width 0.1524)
				(type default)
			)
			(layer "F.SilkS")
		)
		(fp_rect
			(start -0.508 0.9398)
			(end 0.508 -0.9398)
			(stroke
				(width 0)
				(type default)
			)
			(fill no)
			(layer "F.CrtYd")
		)
		(fp_rect
			(start -0.508 0.9398)
			(end 0.508 -0.9398)
			(stroke
				(width 0)
				(type default)
			)
			(fill no)
			(layer "F.Fab")
		)
		(pad "1" smd custom
			(at 0 -0.4445)
			(size 0.1397 0.1397)
			(layers "F.Cu" "F.Mask" "F.Paste")
			(net "P3V3")
			(options
				(clearance outline)
				(anchor circle)
			)
			(primitives
				(gr_poly
					(pts
						(arc
							(start -0.1778 -0.2794)
							(mid -0.249642 -0.249642)
							(end -0.2794 -0.1778)
						)
						(arc
							(start -0.2794 0.1778)
							(mid -0.249642 0.249642)
							(end -0.1778 0.2794)
						)
						(arc
							(start 0.1778 0.2794)
							(mid 0.249642 0.249642)
							(end 0.2794 0.1778)
						)
						(arc
							(start 0.2794 -0.1778)
							(mid 0.249642 -0.249642)
							(end 0.1778 -0.2794)
						)
					)
					(width 0)
					(fill yes)
				)
			)
		)
		(pad "2" smd custom
			(at 0 0.4445)
			(size 0.1397 0.1397)
			(layers "F.Cu" "F.Mask" "F.Paste")
			(net "SAS2X28_A_HDD5_FLT")
			(options
				(clearance outline)
				(anchor circle)
			)
			(primitives
				(gr_poly
					(pts
						(arc
							(start -0.1778 -0.2794)
							(mid -0.249642 -0.249642)
							(end -0.2794 -0.1778)
						)
						(arc
							(start -0.2794 0.1778)
							(mid -0.249642 0.249642)
							(end -0.1778 0.2794)
						)
						(arc
							(start 0.1778 0.2794)
							(mid 0.249642 0.249642)
							(end 0.2794 0.1778)
						)
						(arc
							(start 0.2794 -0.1778)
							(mid 0.249642 -0.249642)
							(end 0.1778 -0.2794)
						)
					)
					(width 0)
					(fill yes)
				)
			)
		)
	)
	(footprint ""
		(layer "F.Cu")
		(at 226.695 -437.261 90)
		(property "Reference" "PC44"
			(at 0 0 90)
			(layer "F.SilkS")
			(hide yes)
			(effects
				(font
					(size 1.27 1.27)
				)
			)
		)
		(property "Value" "SCD1U25V3KX-GP"
			(at 0 -2.8194 90)
			(unlocked yes)
			(layer "F.Fab")
			(hide yes)
			(effects
				(font
					(size 1.016 1.016)
					(thickness 0.1524)
				)
			)
		)
		(property "Device Type" "C603H36"
			(at 0 -4.3434 90)
			(unlocked yes)
			(layer "F.Fab")
			(hide yes)
			(effects
				(font
					(size 1.016 1.016)
					(thickness 0.1524)
				)
			)
		)
		(duplicate_pad_numbers_are_jumpers no)
		(fp_line
			(start 0.508 0)
			(end -0.508 0)
			(stroke
				(width 0.2032)
				(type default)
			)
			(layer "F.SilkS")
		)
		(fp_rect
			(start -0.5842 1.3335)
			(end 0.5842 -1.3335)
			(stroke
				(width 0)
				(type default)
			)
			(fill no)
			(layer "F.CrtYd")
		)
		(fp_rect
			(start -0.5842 1.3335)
			(end 0.5842 -1.3335)
			(stroke
				(width 0)
				(type default)
			)
			(fill no)
			(layer "F.Fab")
		)
		(pad "1" smd custom
			(at 0 -0.762 90)
			(size 0.2159 0.2159)
			(layers "F.Cu" "F.Mask" "F.Paste")
			(net "P3V3_EN")
			(options
				(clearance outline)
				(anchor circle)
			)
			(primitives
				(gr_poly
					(pts
						(arc
							(start -0.3302 -0.4318)
							(mid -0.402042 -0.402042)
							(end -0.4318 -0.3302)
						)
						(arc
							(start -0.4318 0.3302)
							(mid -0.402042 0.402042)
							(end -0.3302 0.4318)
						)
						(arc
							(start 0.3302 0.4318)
							(mid 0.402042 0.402042)
							(end 0.4318 0.3302)
						)
						(arc
							(start 0.4318 -0.3302)
							(mid 0.402042 -0.402042)
							(end 0.3302 -0.4318)
						)
					)
					(width 0)
					(fill yes)
				)
			)
		)
		(pad "2" smd custom
			(at 0 0.762 90)
			(size 0.2159 0.2159)
			(layers "F.Cu" "F.Mask" "F.Paste")
			(net "GND")
			(options
				(clearance outline)
				(anchor circle)
			)
			(primitives
				(gr_poly
					(pts
						(arc
							(start -0.3302 -0.4318)
							(mid -0.402042 -0.402042)
							(end -0.4318 -0.3302)
						)
						(arc
							(start -0.4318 0.3302)
							(mid -0.402042 0.402042)
							(end -0.3302 0.4318)
						)
						(arc
							(start 0.3302 0.4318)
							(mid 0.402042 0.402042)
							(end 0.4318 0.3302)
						)
						(arc
							(start 0.4318 -0.3302)
							(mid 0.402042 -0.402042)
							(end 0.3302 -0.4318)
						)
					)
					(width 0)
					(fill yes)
				)
			)
		)
	)
	(footprint ""
		(layer "F.Cu")
		(at 32.257746 -308.892702 -90)
		(property "Reference" "Q24"
			(at 0 0 270)
			(layer "F.SilkS")
			(hide yes)
			(effects
				(font
					(size 1.27 1.27)
				)
			)
		)
		(property "Value" "2N7002DW-7F-GP"
			(at -2.3622 -8.2042 270)
			(unlocked yes)
			(layer "F.Fab")
			(hide yes)
			(effects
				(font
					(size 1.016 1.016)
					(thickness 0.1524)
				)
			)
		)
		(property "Device Type" "SOT-363H44"
			(at -2.3622 -10.1092 270)
			(unlocked yes)
			(layer "F.Fab")
			(hide yes)
			(effects
				(font
					(size 1.016 1.016)
					(thickness 0.1524)
				)
			)
		)
		(duplicate_pad_numbers_are_jumpers no)
		(fp_line
			(start -1.4478 1.7018)
			(end 1.4478 1.7018)
			(stroke
				(width 0.1524)
				(type default)
			)
			(layer "F.SilkS")
		)
		(fp_line
			(start 1.4478 1.7018)
			(end 1.4478 -1.7018)
			(stroke
				(width 0.1524)
				(type default)
			)
			(layer "F.SilkS")
		)
		(fp_line
			(start -1.27 1.524)
			(end -1.27 0.6604)
			(stroke
				(width 0.4826)
				(type default)
			)
			(layer "F.SilkS")
		)
		(fp_line
			(start -1.4478 -1.7018)
			(end -1.4478 1.7018)
			(stroke
				(width 0.1524)
				(type default)
			)
			(layer "F.SilkS")
		)
		(fp_line
			(start 1.4478 -1.7018)
			(end -1.4478 -1.7018)
			(stroke
				(width 0.1524)
				(type default)
			)
			(layer "F.SilkS")
		)
		(fp_poly
			(pts
				(xy -1.524 -1.778) (xy 1.524 -1.778) (xy 1.524 1.778) (xy -1.524 1.778)
			)
			(stroke
				(width 0)
				(type default)
			)
			(fill no)
			(layer "F.CrtYd")
		)
		(fp_poly
			(pts
				(xy -1.524 -1.778) (xy 1.524 -1.778) (xy 1.524 1.778) (xy -1.524 1.778)
			)
			(stroke
				(width 0)
				(type default)
			)
			(fill no)
			(layer "F.Fab")
		)
		(pad "1" smd rect
			(at -0.65024 0.9398 270)
			(size 0.4064 1.016)
			(layers "F.Cu" "F.Mask" "F.Paste")
			(net "GND")
		)
		(pad "2" smd rect
			(at 0 0.9398 270)
			(size 0.4064 1.016)
			(layers "F.Cu" "F.Mask" "F.Paste")
			(net "SW_PWR_R_HDD11")
		)
		(pad "3" smd rect
			(at 0.65024 0.9398 270)
			(size 0.4064 1.016)
			(layers "F.Cu" "F.Mask" "F.Paste")
			(net "SW_HDD11_P")
		)
		(pad "4" smd rect
			(at 0.65024 -0.9398 270)
			(size 0.4064 1.016)
			(layers "F.Cu" "F.Mask" "F.Paste")
			(net "GND")
		)
		(pad "5" smd rect
			(at 0 -0.9398 270)
			(size 0.4064 1.016)
			(layers "F.Cu" "F.Mask" "F.Paste")
			(net "SW_HDD11_G")
		)
		(pad "6" smd rect
			(at -0.65024 -0.9398 270)
			(size 0.4064 1.016)
			(layers "F.Cu" "F.Mask" "F.Paste")
			(net "SW_HDD11_R")
		)
	)
)
